FILE_TYPE = CONNECTIVITY;
{Allegro Design Entry HDL 16.6-p007 (v16-6-112F) 10/10/2012}
"PAGE_NUMBER" = 58;
0"NC";
1"M_H_DQS_DP<17:0>";
2"M_H_DQS_DN<17:0>";
3"M_H_MA<17:0>";
4"M_H_BA<1:0>";
5"M_H_BG<1:0>";
6"M_H_CKE<3:0>";
7"M_H_CS_N<7:0>";
8"M_H_ODT<3:0>";
9"M_H_DQ<63:0>";
10"M_H_CLK_DN<3:0>";
11"M_H_CLK_DP<3:0>";
12"M_H_ECC<7:0>";
13"M_H_DQ<55>";
14"M_H_DQ<41>";
15"M_H_DQ<52>";
16"M_H_ODT<2>";
17"M_H_DQ<34>";
18"M_H_DQ<32>";
19"M_H_DQ<37>";
20"M_H_C<2>";
21"M_H_ECC<0>";
22"M_H_ECC<1>";
23"M_H_ECC<2>";
24"M_H_ECC<3>";
25"M_H_ECC<4>";
26"M_H_ECC<5>";
27"M_H_ECC<6>";
28"M_H_ECC<7>";
29"M_H_DQ<0>";
30"M_H_DQ<1>";
31"M_H_DQ<2>";
32"M_H_DQ<3>";
33"M_H_DQ<4>";
34"M_H_DQ<5>";
35"M_H_DQ<6>";
36"M_H_DQ<7>";
37"M_H_DQ<8>";
38"M_H_DQ<9>";
39"M_H_DQ<10>";
40"M_H_CLK_DP<0>";
41"M_H_CLK_DP<1>";
42"M_H_CLK_DP<2>";
43"M_H_CLK_DP<3>";
44"M_H_CLK_DN<0>";
45"M_H_CLK_DN<1>";
46"M_H_CLK_DN<2>";
47"M_H_CLK_DN<3>";
48"M_H_DQ<11>";
49"M_H_DQ<12>";
50"M_H_DQ<13>";
51"M_H_DQ<14>";
52"M_H_DQ<15>";
53"M_H_DQ<16>";
54"M_H_DQ<17>";
55"M_H_DQ<18>";
56"M_H_DQ<19>";
57"M_H_DQ<20>";
58"M_H_DQ<21>";
59"M_H_DQ<22>";
60"M_H_DQ<23>";
61"M_H_DQ<24>";
62"M_H_DQ<25>";
63"M_H_DQ<26>";
64"M_H_DQ<27>";
65"M_H_DQ<28>";
66"M_H_DQ<29>";
67"M_H_DQ<30>";
68"M_H_DQ<31>";
69"M_H_DQ<33>";
70"M_H_DQ<35>";
71"M_H_DQ<36>";
72"M_H_DQ<38>";
73"M_H_DQ<39>";
74"M_H_DQ<40>";
75"M_H_DQ<42>";
76"M_H_DQ<43>";
77"M_H_DQ<44>";
78"M_H_DQ<45>";
79"M_H_DQ<46>";
80"M_H_DQ<47>";
81"M_H_DQ<48>";
82"M_H_DQ<49>";
83"M_H_DQ<50>";
84"M_H_DQ<51>";
85"M_H_DQ<53>";
86"M_H_DQ<54>";
87"M_H_DQ<56>";
88"M_H_DQ<57>";
89"M_H_DQ<58>";
90"M_H_DQ<59>";
91"M_H_DQ<60>";
92"M_H_DQ<61>";
93"M_H_DQ<62>";
94"M_H_DQ<63>";
95"M_H_ODT<0>";
96"M_H_ODT<1>";
97"M_H_ODT<3>";
98"M_H_MA<0>";
99"M_H_MA<1>";
100"M_H_MA<2>";
101"M_H_CS_N<0>";
102"M_H_CS_N<1>";
103"M_H_CS_N<2>";
104"M_H_CS_N<3>";
105"M_H_CS_N<4>";
106"M_H_CS_N<5>";
107"M_H_CS_N<6>";
108"M_H_CS_N<7>";
109"M_H_CKE<0>";
110"M_H_CKE<1>";
111"M_H_CKE<2>";
112"M_H_CKE<3>";
113"M_H_BG<0>";
114"M_H_BG<1>";
115"M_H_BA<0>";
116"M_H_BA<1>";
117"M_H_PAR";
118"M_H_ALERT_N";
119"M_H_ACT_N";
120"M_H_MA<3>";
121"M_H_MA<4>";
122"M_H_MA<5>";
123"M_H_MA<6>";
124"M_H_MA<7>";
125"M_H_MA<8>";
126"M_H_MA<9>";
127"M_H_MA<10>";
128"M_H_MA<11>";
129"M_H_MA<12>";
130"M_H_MA<13>";
131"M_H_MA<14>";
132"M_H_MA<15>";
133"M_H_MA<16>";
134"M_H_MA<17>";
135"M_H_DQS_DP<0>";
136"M_H_DQS_DP<1>";
137"M_H_DQS_DP<2>";
138"M_H_DQS_DP<3>";
139"M_H_DQS_DP<4>";
140"M_H_DQS_DP<5>";
141"M_H_DQS_DN<0>";
142"M_H_DQS_DN<1>";
143"M_H_DQS_DN<2>";
144"M_H_DQS_DN<3>";
145"M_H_DQS_DN<4>";
146"M_H_DQS_DN<5>";
147"M_H_DQS_DN<6>";
148"M_H_DQS_DN<7>";
149"M_H_DQS_DN<8>";
150"M_H_DQS_DN<9>";
151"M_H_DQS_DN<10>";
152"M_H_DQS_DN<11>";
153"M_H_DQS_DN<12>";
154"M_H_DQS_DN<13>";
155"M_H_DQS_DN<14>";
156"M_H_DQS_DN<15>";
157"M_H_DQS_DN<16>";
158"M_H_DQS_DN<17>";
159"M_H_DQS_DP<6>";
160"M_H_DQS_DP<7>";
161"M_H_DQS_DP<8>";
162"M_H_DQS_DP<9>";
163"M_H_DQS_DP<10>";
164"M_H_DQS_DP<11>";
165"M_H_DQS_DP<12>";
166"M_H_DQS_DP<13>";
167"M_H_DQS_DP<14>";
168"M_H_DQS_DP<15>";
169"M_H_DQS_DP<16>";
170"M_H_DQS_DP<17>";
%"TAP"
"6","(-5600,825)","0","mstr_standard","I10";
;
CDS_LIB"mstr_standard"
BODY_TYPE"PLUMBING"
HDL_TAP"TRUE";
"B \NAC \NWC"11;
"S \NAC"
BN"0"40;
%"TAP"
"6","(-2875,1575)","2","mstr_standard","I100";
;
CDS_LIB"mstr_standard"
BODY_TYPE"PLUMBING"
HDL_TAP"TRUE";
"B \NAC \NWC"8;
"S \NAC"
BN"3"97;
%"TAP"
"6","(-2875,1525)","2","mstr_standard","I101";
;
CDS_LIB"mstr_standard"
BODY_TYPE"PLUMBING"
HDL_TAP"TRUE";
"B \NAC \NWC"8;
"S \NAC"
BN"2"16;
%"TAP"
"6","(-2875,1475)","2","mstr_standard","I102";
;
CDS_LIB"mstr_standard"
BODY_TYPE"PLUMBING"
HDL_TAP"TRUE";
"B \NAC \NWC"8;
"S \NAC"
BN"1"96;
%"TAP"
"6","(-2875,1675)","2","mstr_standard","I103";
;
CDS_LIB"mstr_standard"
BODY_TYPE"PLUMBING"
HDL_TAP"TRUE";
"B \NAC \NWC"6;
"S \NAC"
BN"0"109;
%"TAP"
"6","(-2875,1725)","2","mstr_standard","I104";
;
CDS_LIB"mstr_standard"
BODY_TYPE"PLUMBING"
HDL_TAP"TRUE";
"B \NAC \NWC"6;
"S \NAC"
BN"1"110;
%"TAP"
"6","(-2875,1775)","2","mstr_standard","I105";
;
CDS_LIB"mstr_standard"
BODY_TYPE"PLUMBING"
HDL_TAP"TRUE";
"B \NAC \NWC"6;
"S \NAC"
BN"2"111;
%"TAP"
"6","(-2875,1825)","2","mstr_standard","I106";
;
CDS_LIB"mstr_standard"
BODY_TYPE"PLUMBING"
HDL_TAP"TRUE";
"B \NAC \NWC"6;
"S \NAC"
BN"3"112;
%"TAP"
"6","(-2875,1925)","2","mstr_standard","I107";
;
CDS_LIB"mstr_standard"
BODY_TYPE"PLUMBING"
HDL_TAP"TRUE";
"B \NAC \NWC"3;
"S \NAC"
BN"0"98;
%"TAP"
"6","(-2875,1975)","2","mstr_standard","I108";
;
CDS_LIB"mstr_standard"
BODY_TYPE"PLUMBING"
HDL_TAP"TRUE";
"B \NAC \NWC"3;
"S \NAC"
BN"1"99;
%"TAP"
"6","(-2875,2075)","2","mstr_standard","I109";
;
CDS_LIB"mstr_standard"
BODY_TYPE"PLUMBING"
HDL_TAP"TRUE";
"B \NAC \NWC"3;
"S \NAC"
BN"3"120;
%"TAP"
"6","(-5600,925)","0","mstr_standard","I11";
;
CDS_LIB"mstr_standard"
BODY_TYPE"PLUMBING"
HDL_TAP"TRUE";
"B \NAC \NWC"11;
"S \NAC"
BN"2"42;
%"TAP"
"6","(-2875,2025)","2","mstr_standard","I110";
;
CDS_LIB"mstr_standard"
BODY_TYPE"PLUMBING"
HDL_TAP"TRUE";
"B \NAC \NWC"3;
"S \NAC"
BN"2"100;
%"TAP"
"6","(-2875,2125)","2","mstr_standard","I111";
;
CDS_LIB"mstr_standard"
BODY_TYPE"PLUMBING"
HDL_TAP"TRUE";
"B \NAC \NWC"3;
"S \NAC"
BN"4"121;
%"TAP"
"6","(-2875,2175)","2","mstr_standard","I112";
;
CDS_LIB"mstr_standard"
BODY_TYPE"PLUMBING"
HDL_TAP"TRUE";
"B \NAC \NWC"3;
"S \NAC"
BN"5"122;
%"TAP"
"6","(-2875,2225)","2","mstr_standard","I113";
;
CDS_LIB"mstr_standard"
BODY_TYPE"PLUMBING"
HDL_TAP"TRUE";
"B \NAC \NWC"3;
"S \NAC"
BN"6"123;
%"TAP"
"6","(-2875,2325)","2","mstr_standard","I114";
;
CDS_LIB"mstr_standard"
BODY_TYPE"PLUMBING"
HDL_TAP"TRUE";
"B \NAC \NWC"3;
"S \NAC"
BN"8"125;
%"TAP"
"6","(-2875,2275)","2","mstr_standard","I115";
;
CDS_LIB"mstr_standard"
BODY_TYPE"PLUMBING"
HDL_TAP"TRUE";
"B \NAC \NWC"3;
"S \NAC"
BN"7"124;
%"TAP"
"6","(-2875,2475)","2","mstr_standard","I116";
;
CDS_LIB"mstr_standard"
BODY_TYPE"PLUMBING"
HDL_TAP"TRUE";
"B \NAC \NWC"3;
"S \NAC"
BN"11"128;
%"TAP"
"6","(-2875,2425)","2","mstr_standard","I117";
;
CDS_LIB"mstr_standard"
BODY_TYPE"PLUMBING"
HDL_TAP"TRUE";
"B \NAC \NWC"3;
"S \NAC"
BN"10"127;
%"TAP"
"6","(-2875,2375)","2","mstr_standard","I118";
;
CDS_LIB"mstr_standard"
BODY_TYPE"PLUMBING"
HDL_TAP"TRUE";
"B \NAC \NWC"3;
"S \NAC"
BN"9"126;
%"TAP"
"6","(-2875,2525)","2","mstr_standard","I119";
;
CDS_LIB"mstr_standard"
BODY_TYPE"PLUMBING"
HDL_TAP"TRUE";
"B \NAC \NWC"3;
"S \NAC"
BN"12"129;
%"TAP"
"6","(-5600,975)","0","mstr_standard","I12";
;
CDS_LIB"mstr_standard"
BODY_TYPE"PLUMBING"
HDL_TAP"TRUE";
"B \NAC \NWC"11;
"S \NAC"
BN"3"43;
%"TAP"
"6","(-2875,2575)","2","mstr_standard","I120";
;
CDS_LIB"mstr_standard"
BODY_TYPE"PLUMBING"
HDL_TAP"TRUE";
"B \NAC \NWC"3;
"S \NAC"
BN"13"130;
%"TAP"
"6","(-2875,2625)","2","mstr_standard","I121";
;
CDS_LIB"mstr_standard"
BODY_TYPE"PLUMBING"
HDL_TAP"TRUE";
"B \NAC \NWC"3;
"S \NAC"
BN"14"131;
%"TAP"
"6","(-2875,2675)","2","mstr_standard","I122";
;
CDS_LIB"mstr_standard"
BODY_TYPE"PLUMBING"
HDL_TAP"TRUE";
"B \NAC \NWC"3;
"S \NAC"
BN"15"132;
%"TAP"
"6","(-2875,2725)","2","mstr_standard","I123";
;
CDS_LIB"mstr_standard"
BODY_TYPE"PLUMBING"
HDL_TAP"TRUE";
"B \NAC \NWC"3;
"S \NAC"
BN"16"133;
%"TAP"
"6","(-2875,2775)","2","mstr_standard","I124";
;
CDS_LIB"mstr_standard"
BODY_TYPE"PLUMBING"
HDL_TAP"TRUE";
"B \NAC \NWC"3;
"S \NAC"
BN"17"134;
%"TAP"
"6","(-2875,2925)","2","mstr_standard","I125";
;
CDS_LIB"mstr_standard"
BODY_TYPE"PLUMBING"
HDL_TAP"TRUE";
"B \NAC \NWC"2;
"S \NAC"
BN"1"142;
%"TAP"
"6","(-2875,2975)","2","mstr_standard","I126";
;
CDS_LIB"mstr_standard"
BODY_TYPE"PLUMBING"
HDL_TAP"TRUE";
"B \NAC \NWC"2;
"S \NAC"
BN"2"143;
%"TAP"
"6","(-2875,2875)","2","mstr_standard","I127";
;
CDS_LIB"mstr_standard"
BODY_TYPE"PLUMBING"
HDL_TAP"TRUE";
"B \NAC \NWC"2;
"S \NAC"
BN"0"141;
%"TAP"
"6","(-2875,3075)","2","mstr_standard","I128";
;
CDS_LIB"mstr_standard"
BODY_TYPE"PLUMBING"
HDL_TAP"TRUE";
"B \NAC \NWC"2;
"S \NAC"
BN"4"145;
%"TAP"
"6","(-2875,3025)","2","mstr_standard","I129";
;
CDS_LIB"mstr_standard"
BODY_TYPE"PLUMBING"
HDL_TAP"TRUE";
"B \NAC \NWC"2;
"S \NAC"
BN"3"144;
%"TAP"
"6","(-5600,1075)","0","mstr_standard","I13";
;
CDS_LIB"mstr_standard"
BODY_TYPE"PLUMBING"
HDL_TAP"TRUE";
"B \NAC \NWC"12;
"S \NAC"
BN"0"21;
%"TAP"
"6","(-2875,3125)","2","mstr_standard","I130";
;
CDS_LIB"mstr_standard"
BODY_TYPE"PLUMBING"
HDL_TAP"TRUE";
"B \NAC \NWC"2;
"S \NAC"
BN"5"146;
%"TAP"
"6","(-2875,3175)","2","mstr_standard","I131";
;
CDS_LIB"mstr_standard"
BODY_TYPE"PLUMBING"
HDL_TAP"TRUE";
"B \NAC \NWC"2;
"S \NAC"
BN"6"147;
%"TAP"
"6","(-2875,3225)","2","mstr_standard","I132";
;
CDS_LIB"mstr_standard"
BODY_TYPE"PLUMBING"
HDL_TAP"TRUE";
"B \NAC \NWC"2;
"S \NAC"
BN"7"148;
%"TAP"
"6","(-2875,3275)","2","mstr_standard","I133";
;
CDS_LIB"mstr_standard"
BODY_TYPE"PLUMBING"
HDL_TAP"TRUE";
"B \NAC \NWC"2;
"S \NAC"
BN"8"149;
%"TAP"
"6","(-2875,3325)","2","mstr_standard","I134";
;
CDS_LIB"mstr_standard"
BODY_TYPE"PLUMBING"
HDL_TAP"TRUE";
"B \NAC \NWC"2;
"S \NAC"
BN"9"150;
%"TAP"
"6","(-2875,3375)","2","mstr_standard","I135";
;
CDS_LIB"mstr_standard"
BODY_TYPE"PLUMBING"
HDL_TAP"TRUE";
"B \NAC \NWC"2;
"S \NAC"
BN"10"151;
%"TAP"
"6","(-2875,3475)","2","mstr_standard","I136";
;
CDS_LIB"mstr_standard"
BODY_TYPE"PLUMBING"
HDL_TAP"TRUE";
"B \NAC \NWC"2;
"S \NAC"
BN"12"153;
%"TAP"
"6","(-2875,3425)","2","mstr_standard","I137";
;
CDS_LIB"mstr_standard"
BODY_TYPE"PLUMBING"
HDL_TAP"TRUE";
"B \NAC \NWC"2;
"S \NAC"
BN"11"152;
%"TAP"
"6","(-2875,3625)","2","mstr_standard","I138";
;
CDS_LIB"mstr_standard"
BODY_TYPE"PLUMBING"
HDL_TAP"TRUE";
"B \NAC \NWC"2;
"S \NAC"
BN"15"156;
%"TAP"
"6","(-2875,3575)","2","mstr_standard","I139";
;
CDS_LIB"mstr_standard"
BODY_TYPE"PLUMBING"
HDL_TAP"TRUE";
"B \NAC \NWC"2;
"S \NAC"
BN"14"155;
%"TAP"
"6","(-5600,1125)","0","mstr_standard","I14";
;
CDS_LIB"mstr_standard"
BODY_TYPE"PLUMBING"
HDL_TAP"TRUE";
"B \NAC \NWC"12;
"S \NAC"
BN"1"22;
%"TAP"
"6","(-2875,3525)","2","mstr_standard","I140";
;
CDS_LIB"mstr_standard"
BODY_TYPE"PLUMBING"
HDL_TAP"TRUE";
"B \NAC \NWC"2;
"S \NAC"
BN"13"154;
%"TAP"
"6","(-2875,3675)","2","mstr_standard","I141";
;
CDS_LIB"mstr_standard"
BODY_TYPE"PLUMBING"
HDL_TAP"TRUE";
"B \NAC \NWC"2;
"S \NAC"
BN"16"157;
%"TAP"
"6","(-2875,3725)","2","mstr_standard","I142";
;
CDS_LIB"mstr_standard"
BODY_TYPE"PLUMBING"
HDL_TAP"TRUE";
"B \NAC \NWC"2;
"S \NAC"
BN"17"158;
%"TAP"
"6","(-2875,3825)","2","mstr_standard","I143";
;
CDS_LIB"mstr_standard"
BODY_TYPE"PLUMBING"
HDL_TAP"TRUE";
"B \NAC \NWC"1;
"S \NAC"
BN"0"135;
%"TAP"
"6","(-2875,3875)","2","mstr_standard","I144";
;
CDS_LIB"mstr_standard"
BODY_TYPE"PLUMBING"
HDL_TAP"TRUE";
"B \NAC \NWC"1;
"S \NAC"
BN"1"136;
%"TAP"
"6","(-2875,3925)","2","mstr_standard","I145";
;
CDS_LIB"mstr_standard"
BODY_TYPE"PLUMBING"
HDL_TAP"TRUE";
"B \NAC \NWC"1;
"S \NAC"
BN"2"137;
%"TAP"
"6","(-2875,3975)","2","mstr_standard","I146";
;
CDS_LIB"mstr_standard"
BODY_TYPE"PLUMBING"
HDL_TAP"TRUE";
"B \NAC \NWC"1;
"S \NAC"
BN"3"138;
%"TAP"
"6","(-5600,1175)","0","mstr_standard","I15";
;
CDS_LIB"mstr_standard"
BODY_TYPE"PLUMBING"
HDL_TAP"TRUE";
"B \NAC \NWC"12;
"S \NAC"
BN"2"23;
%"TAP"
"6","(-2875,4025)","2","mstr_standard","I157";
;
CDS_LIB"mstr_standard"
BODY_TYPE"PLUMBING"
HDL_TAP"TRUE";
"B \NAC \NWC"1;
"S \NAC"
BN"4"139;
%"TAP"
"6","(-2875,4125)","2","mstr_standard","I158";
;
CDS_LIB"mstr_standard"
BODY_TYPE"PLUMBING"
HDL_TAP"TRUE";
"B \NAC \NWC"1;
"S \NAC"
BN"6"159;
%"TAP"
"6","(-2875,4075)","2","mstr_standard","I159";
;
CDS_LIB"mstr_standard"
BODY_TYPE"PLUMBING"
HDL_TAP"TRUE";
"B \NAC \NWC"1;
"S \NAC"
BN"5"140;
%"TAP"
"6","(-5600,1275)","0","mstr_standard","I16";
;
CDS_LIB"mstr_standard"
BODY_TYPE"PLUMBING"
HDL_TAP"TRUE";
"B \NAC \NWC"12;
"S \NAC"
BN"4"25;
%"TAP"
"6","(-2875,4175)","2","mstr_standard","I160";
;
CDS_LIB"mstr_standard"
BODY_TYPE"PLUMBING"
HDL_TAP"TRUE";
"B \NAC \NWC"1;
"S \NAC"
BN"7"160;
%"TAP"
"6","(-2875,4225)","2","mstr_standard","I161";
;
CDS_LIB"mstr_standard"
BODY_TYPE"PLUMBING"
HDL_TAP"TRUE";
"B \NAC \NWC"1;
"S \NAC"
BN"8"161;
%"TAP"
"6","(-2875,4275)","2","mstr_standard","I162";
;
CDS_LIB"mstr_standard"
BODY_TYPE"PLUMBING"
HDL_TAP"TRUE";
"B \NAC \NWC"1;
"S \NAC"
BN"9"162;
%"TAP"
"6","(-2875,4325)","2","mstr_standard","I163";
;
CDS_LIB"mstr_standard"
BODY_TYPE"PLUMBING"
HDL_TAP"TRUE";
"B \NAC \NWC"1;
"S \NAC"
BN"10"163;
%"TAP"
"6","(-2875,4375)","2","mstr_standard","I164";
;
CDS_LIB"mstr_standard"
BODY_TYPE"PLUMBING"
HDL_TAP"TRUE";
"B \NAC \NWC"1;
"S \NAC"
BN"11"164;
%"TAP"
"6","(-2875,4525)","2","mstr_standard","I165";
;
CDS_LIB"mstr_standard"
BODY_TYPE"PLUMBING"
HDL_TAP"TRUE";
"B \NAC \NWC"1;
"S \NAC"
BN"14"167;
%"TAP"
"6","(-2875,4475)","2","mstr_standard","I166";
;
CDS_LIB"mstr_standard"
BODY_TYPE"PLUMBING"
HDL_TAP"TRUE";
"B \NAC \NWC"1;
"S \NAC"
BN"13"166;
%"TAP"
"6","(-2875,4425)","2","mstr_standard","I167";
;
CDS_LIB"mstr_standard"
BODY_TYPE"PLUMBING"
HDL_TAP"TRUE";
"B \NAC \NWC"1;
"S \NAC"
BN"12"165;
%"TAP"
"6","(-2875,4575)","2","mstr_standard","I168";
;
CDS_LIB"mstr_standard"
BODY_TYPE"PLUMBING"
HDL_TAP"TRUE";
"B \NAC \NWC"1;
"S \NAC"
BN"15"168;
%"TAP"
"6","(-2875,4625)","2","mstr_standard","I169";
;
CDS_LIB"mstr_standard"
BODY_TYPE"PLUMBING"
HDL_TAP"TRUE";
"B \NAC \NWC"1;
"S \NAC"
BN"16"169;
%"TAP"
"6","(-5600,1225)","0","mstr_standard","I17";
;
CDS_LIB"mstr_standard"
BODY_TYPE"PLUMBING"
HDL_TAP"TRUE";
"B \NAC \NWC"12;
"S \NAC"
BN"3"24;
%"TAP"
"6","(-2875,4675)","2","mstr_standard","I170";
;
CDS_LIB"mstr_standard"
BODY_TYPE"PLUMBING"
HDL_TAP"TRUE";
"B \NAC \NWC"1;
"S \NAC"
BN"17"170;
%"SKX_EXT_B"
"4","(-4200,2575)","0","chpset_lib","I172";
;
CDS_SEC"4"
LOCATION"U2D1"
PART_NUMBER"TBD"
MATERIAL"IC"
PACK_TYPE"BGA1"
SEC_TYPE"BGA1"
CDS_LIB"chpset_lib"
SEC"4"
CDS_LOCATION"U2D1";
"DDR1_PAR"
$PN"K53"117;
"DDR1_ODT<0>"
$PN"N50"95;
"DDR1_ODT<1>"
$PN"R48"96;
"DDR1_ODT<2>"
$PN"M49"16;
"DDR1_ODT<3>"
$PN"T47"97;
"DDR1_MA<0>"
$PN"J52"98;
"DDR1_MA<1>"
$PN"J58"99;
"DDR1_MA<2>"
$PN"K57"100;
"DDR1_MA<3>"
$PN"N58"120;
"DDR1_MA<4>"
$PN"M59"121;
"DDR1_MA<5>"
$PN"R58"122;
"DDR1_MA<6>"
$PN"T59"123;
"DDR1_MA<7>"
$PN"V61"124;
"DDR1_MA<8>"
$PN"W60"125;
"DDR1_MA<9>"
$PN"K59"126;
"DDR1_MA<10>"
$PN"M55"127;
"DDR1_MA<11>"
$PN"R60"128;
"DDR1_MA<12>"
$PN"T61"129;
"DDR1_MA<13>"
$PN"M51"130;
"DDR1_MA<14>"
$PN"T51"131;
"DDR1_MA<15>"
$PN"N52"132;
"DDR1_MA<16>"
$PN"R52"133;
"DDR1_MA<17>"
$PN"N48"134;
"DDR1_ECC<0>"
$PN"J70"21;
"DDR1_ECC<1>"
$PN"H69"22;
"DDR1_ECC<2>"
$PN"J66"23;
"DDR1_ECC<3>"
$PN"L66"24;
"DDR1_ECC<4>"
$PN"L70"25;
"DDR1_ECC<5>"
$PN"M69"26;
"DDR1_ECC<6>"
$PN"H67"27;
"DDR1_ECC<7>"
$PN"M67"28;
"DDR1_DQS_DP<0>"
$PN"AR80"135;
"DDR1_DQS_DP<1>"
$PN"AE80"136;
"DDR1_DQS_DP<2>"
$PN"H79"137;
"DDR1_DQS_DP<3>"
$PN"F73"138;
"DDR1_DQS_DP<4>"
$PN"R42"139;
"DDR1_DQS_DP<5>"
$PN"E34"140;
"DDR1_DQS_DP<6>"
$PN"E28"159;
"DDR1_DQS_DP<7>"
$PN"Y27"160;
"DDR1_DQS_DP<8>"
$PN"L68"161;
"DDR1_DQS_DP<9>"
$PN"AT81"162;
"DDR1_DQS_DP<10>"
$PN"AF81"163;
"DDR1_DQS_DP<11>"
$PN"F79"164;
"DDR1_DQS_DP<12>"
$PN"D73"165;
"DDR1_DQS_DP<13>"
$PN"L42"166;
"DDR1_DQS_DP<14>"
$PN"C34"167;
"DDR1_DQS_DP<15>"
$PN"C28"168;
"DDR1_DQS_DP<16>"
$PN"V27"169;
"DDR1_DQS_DP<17>"
$PN"J68"170;
"DDR1_DQS_DN<0>"
$PN"AP79"141;
"DDR1_DQS_DN<1>"
$PN"AD79"142;
"DDR1_DQS_DN<2>"
$PN"K79"143;
"DDR1_DQS_DN<3>"
$PN"H73"144;
"DDR1_DQS_DN<4>"
$PN"N42"145;
"DDR1_DQS_DN<5>"
$PN"G34"146;
"DDR1_DQS_DN<6>"
$PN"G28"147;
"DDR1_DQS_DN<7>"
$PN"AB27"148;
"DDR1_DQS_DN<8>"
$PN"N68"149;
"DDR1_DQS_DN<9>"
$PN"AU82"150;
"DDR1_DQS_DN<10>"
$PN"AG82"151;
"DDR1_DQS_DN<11>"
$PN"D79"152;
"DDR1_DQS_DN<12>"
$PN"B73"153;
"DDR1_DQS_DN<13>"
$PN"J42"154;
"DDR1_DQS_DN<14>"
$PN"A34"155;
"DDR1_DQS_DN<15>"
$PN"A28"156;
"DDR1_DQS_DN<16>"
$PN"T27"157;
"DDR1_DQS_DN<17>"
$PN"G68"158;
"DDR1_DQ<0>"
$PN"AV81"29;
"DDR1_DQ<1>"
$PN"AT79"30;
"DDR1_DQ<2>"
$PN"AN82"31;
"DDR1_DQ<3>"
$PN"AM81"32;
"DDR1_DQ<4>"
$PN"AW80"33;
"DDR1_DQ<5>"
$PN"AV79"34;
"DDR1_DQ<6>"
$PN"AR82"35;
"DDR1_DQ<7>"
$PN"AN80"36;
"DDR1_DQ<8>"
$PN"AH81"37;
"DDR1_DQ<9>"
$PN"AF79"38;
"DDR1_DQ<10>"
$PN"AC82"39;
"DDR1_DQ<11>"
$PN"AB81"48;
"DDR1_DQ<12>"
$PN"AJ80"49;
"DDR1_DQ<13>"
$PN"AH79"50;
"DDR1_DQ<14>"
$PN"AE82"51;
"DDR1_DQ<15>"
$PN"AC80"52;
"DDR1_DQ<16>"
$PN"E80"53;
"DDR1_DQ<17>"
$PN"J80"54;
"DDR1_DQ<18>"
$PN"F77"55;
"DDR1_DQ<19>"
$PN"H77"56;
"DDR1_DQ<20>"
$PN"F81"57;
"DDR1_DQ<21>"
$PN"H81"58;
"DDR1_DQ<22>"
$PN"E78"59;
"DDR1_DQ<23>"
$PN"J78"60;
"DDR1_DQ<24>"
$PN"D75"61;
"DDR1_DQ<25>"
$PN"C74"62;
"DDR1_DQ<26>"
$PN"D71"63;
"DDR1_DQ<27>"
$PN"F71"64;
"DDR1_DQ<28>"
$PN"F75"65;
"DDR1_DQ<29>"
$PN"G74"66;
"DDR1_DQ<30>"
$PN"C72"67;
"DDR1_DQ<31>"
$PN"G72"68;
"DDR1_DQ<32>"
$PN"K43"18;
"DDR1_DQ<33>"
$PN"H43"69;
"DDR1_DQ<34>"
$PN"L40"17;
"DDR1_DQ<35>"
$PN"N40"70;
"DDR1_DQ<36>"
$PN"P43"71;
"DDR1_DQ<37>"
$PN"T43"19;
"DDR1_DQ<38>"
$PN"K41"72;
"DDR1_DQ<39>"
$PN"P41"73;
"DDR1_DQ<40>"
$PN"C36"74;
"DDR1_DQ<41>"
$PN"B35"14;
"DDR1_DQ<42>"
$PN"C32"75;
"DDR1_DQ<43>"
$PN"E32"76;
"DDR1_DQ<44>"
$PN"E36"77;
"DDR1_DQ<45>"
$PN"F35"78;
"DDR1_DQ<46>"
$PN"B33"79;
"DDR1_DQ<47>"
$PN"F33"80;
"DDR1_DQ<48>"
$PN"C30"81;
"DDR1_DQ<49>"
$PN"B29"82;
"DDR1_DQ<50>"
$PN"C26"83;
"DDR1_DQ<51>"
$PN"E26"84;
"DDR1_DQ<52>"
$PN"E30"15;
"DDR1_DQ<53>"
$PN"F29"85;
"DDR1_DQ<54>"
$PN"B27"86;
"DDR1_DQ<55>"
$PN"F27"13;
"DDR1_DQ<56>"
$PN"U28"87;
"DDR1_DQ<57>"
$PN"AA28"88;
"DDR1_DQ<58>"
$PN"V25"89;
"DDR1_DQ<59>"
$PN"Y25"90;
"DDR1_DQ<60>"
$PN"V29"91;
"DDR1_DQ<61>"
$PN"Y29"92;
"DDR1_DQ<62>"
$PN"U26"93;
"DDR1_DQ<63>"
$PN"AA26"94;
"DDR1_CS_N<0>"
$PN"K51"101;
"DDR1_CS_N<1>"
$PN"R50"102;
"DDR1_CS_N<2>"
$PN"N46"103;
"DDR1_CS_N<3>"
$PN"V47"104;
"DDR1_CS_N<4>"
$PN"J50"105;
"DDR1_CS_N<5>"
$PN"T49"106;
"DDR1_CS_N<6>"
$PN"M45"107;
"DDR1_CS_N<7>"
$PN"R46"108;
"DDR1_CLK_DP<0>"
$PN"N54"40;
"DDR1_CLK_DP<1>"
$PN"T55"41;
"DDR1_CLK_DP<2>"
$PN"M57"42;
"DDR1_CLK_DP<3>"
$PN"T57"43;
"DDR1_CLK_DN<0>"
$PN"M53"44;
"DDR1_CLK_DN<1>"
$PN"R54"45;
"DDR1_CLK_DN<2>"
$PN"N56"46;
"DDR1_CLK_DN<3>"
$PN"R56"47;
"DDR1_CKE<0>"
$PN"N62"109;
"DDR1_CKE<1>"
$PN"R64"110;
"DDR1_CKE<2>"
$PN"K63"111;
"DDR1_CKE<3>"
$PN"L64"112;
"DDR1_CID<2>"
$PN"M47"20;
"DDR1_BG<0>"
$PN"M61"113;
"DDR1_BG<1>"
$PN"N60"114;
"DDR1_BA<0>"
$PN"T53"115;
"DDR1_BA<1>"
$PN"K55"116;
"DDR1_ALERT_N"
$PN"W62"118;
"DDR1_ACT_N"
$PN"T63"119;
%"TAP"
"6","(-5600,1325)","0","mstr_standard","I18";
;
CDS_LIB"mstr_standard"
BODY_TYPE"PLUMBING"
HDL_TAP"TRUE";
"B \NAC \NWC"12;
"S \NAC"
BN"5"26;
%"TAP"
"6","(-5600,1375)","0","mstr_standard","I19";
;
CDS_LIB"mstr_standard"
BODY_TYPE"PLUMBING"
HDL_TAP"TRUE";
"B \NAC \NWC"12;
"S \NAC"
BN"6"27;
%"TAP"
"6","(-5600,1425)","0","mstr_standard","I20";
;
CDS_LIB"mstr_standard"
BODY_TYPE"PLUMBING"
HDL_TAP"TRUE";
"B \NAC \NWC"12;
"S \NAC"
BN"7"28;
%"TAP"
"6","(-5600,1525)","0","mstr_standard","I21";
;
CDS_LIB"mstr_standard"
BODY_TYPE"PLUMBING"
HDL_TAP"TRUE";
"B \NAC \NWC"9;
"S \NAC"
BN"0"29;
%"TAP"
"6","(-5600,1575)","0","mstr_standard","I22";
;
CDS_LIB"mstr_standard"
BODY_TYPE"PLUMBING"
HDL_TAP"TRUE";
"B \NAC \NWC"9;
"S \NAC"
BN"1"30;
%"TAP"
"6","(-5600,1625)","0","mstr_standard","I23";
;
CDS_LIB"mstr_standard"
BODY_TYPE"PLUMBING"
HDL_TAP"TRUE";
"B \NAC \NWC"9;
"S \NAC"
BN"2"31;
%"TAP"
"6","(-5600,1675)","0","mstr_standard","I24";
;
CDS_LIB"mstr_standard"
BODY_TYPE"PLUMBING"
HDL_TAP"TRUE";
"B \NAC \NWC"9;
"S \NAC"
BN"3"32;
%"TAP"
"6","(-5600,1725)","0","mstr_standard","I25";
;
CDS_LIB"mstr_standard"
BODY_TYPE"PLUMBING"
HDL_TAP"TRUE";
"B \NAC \NWC"9;
"S \NAC"
BN"4"33;
%"TAP"
"6","(-5600,1775)","0","mstr_standard","I26";
;
CDS_LIB"mstr_standard"
BODY_TYPE"PLUMBING"
HDL_TAP"TRUE";
"B \NAC \NWC"9;
"S \NAC"
BN"5"34;
%"TAP"
"6","(-5600,1825)","0","mstr_standard","I27";
;
CDS_LIB"mstr_standard"
BODY_TYPE"PLUMBING"
HDL_TAP"TRUE";
"B \NAC \NWC"9;
"S \NAC"
BN"6"35;
%"TAP"
"6","(-5600,1925)","0","mstr_standard","I28";
;
CDS_LIB"mstr_standard"
BODY_TYPE"PLUMBING"
HDL_TAP"TRUE";
"B \NAC \NWC"9;
"S \NAC"
BN"8"37;
%"TAP"
"6","(-5600,1875)","0","mstr_standard","I29";
;
CDS_LIB"mstr_standard"
BODY_TYPE"PLUMBING"
HDL_TAP"TRUE";
"B \NAC \NWC"9;
"S \NAC"
BN"7"36;
%"TAP"
"6","(-5600,1975)","0","mstr_standard","I31";
;
CDS_LIB"mstr_standard"
BODY_TYPE"PLUMBING"
HDL_TAP"TRUE";
"B \NAC \NWC"9;
"S \NAC"
BN"9"38;
%"TAP"
"6","(-5600,2025)","0","mstr_standard","I32";
;
CDS_LIB"mstr_standard"
BODY_TYPE"PLUMBING"
HDL_TAP"TRUE";
"B \NAC \NWC"9;
"S \NAC"
BN"10"39;
%"TAP"
"6","(-5600,2075)","0","mstr_standard","I33";
;
CDS_LIB"mstr_standard"
BODY_TYPE"PLUMBING"
HDL_TAP"TRUE";
"B \NAC \NWC"9;
"S \NAC"
BN"11"48;
%"TAP"
"6","(-5600,2125)","0","mstr_standard","I34";
;
CDS_LIB"mstr_standard"
BODY_TYPE"PLUMBING"
HDL_TAP"TRUE";
"B \NAC \NWC"9;
"S \NAC"
BN"12"49;
%"TAP"
"6","(-5600,2175)","0","mstr_standard","I35";
;
CDS_LIB"mstr_standard"
BODY_TYPE"PLUMBING"
HDL_TAP"TRUE";
"B \NAC \NWC"9;
"S \NAC"
BN"13"50;
%"TAP"
"6","(-5600,2225)","0","mstr_standard","I36";
;
CDS_LIB"mstr_standard"
BODY_TYPE"PLUMBING"
HDL_TAP"TRUE";
"B \NAC \NWC"9;
"S \NAC"
BN"14"51;
%"TAP"
"6","(-5600,2275)","0","mstr_standard","I37";
;
CDS_LIB"mstr_standard"
BODY_TYPE"PLUMBING"
HDL_TAP"TRUE";
"B \NAC \NWC"9;
"S \NAC"
BN"15"52;
%"TAP"
"6","(-5600,2325)","0","mstr_standard","I38";
;
CDS_LIB"mstr_standard"
BODY_TYPE"PLUMBING"
HDL_TAP"TRUE";
"B \NAC \NWC"9;
"S \NAC"
BN"16"53;
%"TAP"
"6","(-5600,2375)","0","mstr_standard","I39";
;
CDS_LIB"mstr_standard"
BODY_TYPE"PLUMBING"
HDL_TAP"TRUE";
"B \NAC \NWC"9;
"S \NAC"
BN"17"54;
%"TAP"
"6","(-5600,2425)","0","mstr_standard","I40";
;
CDS_LIB"mstr_standard"
BODY_TYPE"PLUMBING"
HDL_TAP"TRUE";
"B \NAC \NWC"9;
"S \NAC"
BN"18"55;
%"TAP"
"6","(-5600,2475)","0","mstr_standard","I41";
;
CDS_LIB"mstr_standard"
BODY_TYPE"PLUMBING"
HDL_TAP"TRUE";
"B \NAC \NWC"9;
"S \NAC"
BN"19"56;
%"TAP"
"6","(-5600,2525)","0","mstr_standard","I42";
;
CDS_LIB"mstr_standard"
BODY_TYPE"PLUMBING"
HDL_TAP"TRUE";
"B \NAC \NWC"9;
"S \NAC"
BN"20"57;
%"TAP"
"6","(-5600,2575)","0","mstr_standard","I43";
;
CDS_LIB"mstr_standard"
BODY_TYPE"PLUMBING"
HDL_TAP"TRUE";
"B \NAC \NWC"9;
"S \NAC"
BN"21"58;
%"TAP"
"6","(-5600,2625)","0","mstr_standard","I44";
;
CDS_LIB"mstr_standard"
BODY_TYPE"PLUMBING"
HDL_TAP"TRUE";
"B \NAC \NWC"9;
"S \NAC"
BN"22"59;
%"TAP"
"6","(-5600,2675)","0","mstr_standard","I45";
;
CDS_LIB"mstr_standard"
BODY_TYPE"PLUMBING"
HDL_TAP"TRUE";
"B \NAC \NWC"9;
"S \NAC"
BN"23"60;
%"TAP"
"6","(-5600,2725)","0","mstr_standard","I46";
;
CDS_LIB"mstr_standard"
BODY_TYPE"PLUMBING"
HDL_TAP"TRUE";
"B \NAC \NWC"9;
"S \NAC"
BN"24"61;
%"TAP"
"6","(-5600,2825)","0","mstr_standard","I47";
;
CDS_LIB"mstr_standard"
BODY_TYPE"PLUMBING"
HDL_TAP"TRUE";
"B \NAC \NWC"9;
"S \NAC"
BN"26"63;
%"TAP"
"6","(-5600,2775)","0","mstr_standard","I48";
;
CDS_LIB"mstr_standard"
BODY_TYPE"PLUMBING"
HDL_TAP"TRUE";
"B \NAC \NWC"9;
"S \NAC"
BN"25"62;
%"TAP"
"6","(-5600,2875)","0","mstr_standard","I49";
;
CDS_LIB"mstr_standard"
BODY_TYPE"PLUMBING"
HDL_TAP"TRUE";
"B \NAC \NWC"9;
"S \NAC"
BN"27"64;
%"TAP"
"6","(-5600,625)","0","mstr_standard","I5";
;
CDS_LIB"mstr_standard"
BODY_TYPE"PLUMBING"
HDL_TAP"TRUE";
"B \NAC \NWC"10;
"S \NAC"
BN"0"44;
%"TAP"
"6","(-5600,2925)","0","mstr_standard","I50";
;
CDS_LIB"mstr_standard"
BODY_TYPE"PLUMBING"
HDL_TAP"TRUE";
"B \NAC \NWC"9;
"S \NAC"
BN"28"65;
%"TAP"
"6","(-5600,2975)","0","mstr_standard","I51";
;
CDS_LIB"mstr_standard"
BODY_TYPE"PLUMBING"
HDL_TAP"TRUE";
"B \NAC \NWC"9;
"S \NAC"
BN"29"66;
%"TAP"
"6","(-5600,3075)","0","mstr_standard","I52";
;
CDS_LIB"mstr_standard"
BODY_TYPE"PLUMBING"
HDL_TAP"TRUE";
"B \NAC \NWC"9;
"S \NAC"
BN"31"68;
%"TAP"
"6","(-5600,3025)","0","mstr_standard","I53";
;
CDS_LIB"mstr_standard"
BODY_TYPE"PLUMBING"
HDL_TAP"TRUE";
"B \NAC \NWC"9;
"S \NAC"
BN"30"67;
%"TAP"
"6","(-5600,3125)","0","mstr_standard","I54";
;
CDS_LIB"mstr_standard"
BODY_TYPE"PLUMBING"
HDL_TAP"TRUE";
"B \NAC \NWC"9;
"S \NAC"
BN"32"18;
%"TAP"
"6","(-5600,3175)","0","mstr_standard","I55";
;
CDS_LIB"mstr_standard"
BODY_TYPE"PLUMBING"
HDL_TAP"TRUE";
"B \NAC \NWC"9;
"S \NAC"
BN"33"69;
%"TAP"
"6","(-5600,3225)","0","mstr_standard","I56";
;
CDS_LIB"mstr_standard"
BODY_TYPE"PLUMBING"
HDL_TAP"TRUE";
"B \NAC \NWC"9;
"S \NAC"
BN"34"17;
%"TAP"
"6","(-5600,3325)","0","mstr_standard","I57";
;
CDS_LIB"mstr_standard"
BODY_TYPE"PLUMBING"
HDL_TAP"TRUE";
"B \NAC \NWC"9;
"S \NAC"
BN"36"71;
%"TAP"
"6","(-5600,3275)","0","mstr_standard","I58";
;
CDS_LIB"mstr_standard"
BODY_TYPE"PLUMBING"
HDL_TAP"TRUE";
"B \NAC \NWC"9;
"S \NAC"
BN"35"70;
%"TAP"
"6","(-5600,3375)","0","mstr_standard","I59";
;
CDS_LIB"mstr_standard"
BODY_TYPE"PLUMBING"
HDL_TAP"TRUE";
"B \NAC \NWC"9;
"S \NAC"
BN"37"19;
%"TAP"
"6","(-5600,675)","0","mstr_standard","I6";
;
CDS_LIB"mstr_standard"
BODY_TYPE"PLUMBING"
HDL_TAP"TRUE";
"B \NAC \NWC"10;
"S \NAC"
BN"1"45;
%"TAP"
"6","(-5600,3425)","0","mstr_standard","I60";
;
CDS_LIB"mstr_standard"
BODY_TYPE"PLUMBING"
HDL_TAP"TRUE";
"B \NAC \NWC"9;
"S \NAC"
BN"38"72;
%"TAP"
"6","(-5600,3475)","0","mstr_standard","I61";
;
CDS_LIB"mstr_standard"
BODY_TYPE"PLUMBING"
HDL_TAP"TRUE";
"B \NAC \NWC"9;
"S \NAC"
BN"39"73;
%"TAP"
"6","(-5600,3525)","0","mstr_standard","I62";
;
CDS_LIB"mstr_standard"
BODY_TYPE"PLUMBING"
HDL_TAP"TRUE";
"B \NAC \NWC"9;
"S \NAC"
BN"40"74;
%"TAP"
"6","(-5600,3575)","0","mstr_standard","I63";
;
CDS_LIB"mstr_standard"
BODY_TYPE"PLUMBING"
HDL_TAP"TRUE";
"B \NAC \NWC"9;
"S \NAC"
BN"41"14;
%"TAP"
"6","(-5600,3625)","0","mstr_standard","I64";
;
CDS_LIB"mstr_standard"
BODY_TYPE"PLUMBING"
HDL_TAP"TRUE";
"B \NAC \NWC"9;
"S \NAC"
BN"42"75;
%"TAP"
"6","(-5600,3675)","0","mstr_standard","I65";
;
CDS_LIB"mstr_standard"
BODY_TYPE"PLUMBING"
HDL_TAP"TRUE";
"B \NAC \NWC"9;
"S \NAC"
BN"43"76;
%"TAP"
"6","(-5600,3725)","0","mstr_standard","I66";
;
CDS_LIB"mstr_standard"
BODY_TYPE"PLUMBING"
HDL_TAP"TRUE";
"B \NAC \NWC"9;
"S \NAC"
BN"44"77;
%"TAP"
"6","(-5600,3775)","0","mstr_standard","I67";
;
CDS_LIB"mstr_standard"
BODY_TYPE"PLUMBING"
HDL_TAP"TRUE";
"B \NAC \NWC"9;
"S \NAC"
BN"45"78;
%"TAP"
"6","(-5600,3825)","0","mstr_standard","I68";
;
CDS_LIB"mstr_standard"
BODY_TYPE"PLUMBING"
HDL_TAP"TRUE";
"B \NAC \NWC"9;
"S \NAC"
BN"46"79;
%"TAP"
"6","(-5600,3875)","0","mstr_standard","I69";
;
CDS_LIB"mstr_standard"
BODY_TYPE"PLUMBING"
HDL_TAP"TRUE";
"B \NAC \NWC"9;
"S \NAC"
BN"47"80;
%"TAP"
"6","(-5600,775)","0","mstr_standard","I7";
;
CDS_LIB"mstr_standard"
BODY_TYPE"PLUMBING"
HDL_TAP"TRUE";
"B \NAC \NWC"10;
"S \NAC"
BN"3"47;
%"TAP"
"6","(-5600,3925)","0","mstr_standard","I70";
;
CDS_LIB"mstr_standard"
BODY_TYPE"PLUMBING"
HDL_TAP"TRUE";
"B \NAC \NWC"9;
"S \NAC"
BN"48"81;
%"TAP"
"6","(-5600,3975)","0","mstr_standard","I71";
;
CDS_LIB"mstr_standard"
BODY_TYPE"PLUMBING"
HDL_TAP"TRUE";
"B \NAC \NWC"9;
"S \NAC"
BN"49"82;
%"TAP"
"6","(-5600,4025)","0","mstr_standard","I73";
;
CDS_LIB"mstr_standard"
BODY_TYPE"PLUMBING"
HDL_TAP"TRUE";
"B \NAC \NWC"9;
"S \NAC"
BN"50"83;
%"TAP"
"6","(-5600,4075)","0","mstr_standard","I74";
;
CDS_LIB"mstr_standard"
BODY_TYPE"PLUMBING"
HDL_TAP"TRUE";
"B \NAC \NWC"9;
"S \NAC"
BN"51"84;
%"TAP"
"6","(-5600,4125)","0","mstr_standard","I75";
;
CDS_LIB"mstr_standard"
BODY_TYPE"PLUMBING"
HDL_TAP"TRUE";
"B \NAC \NWC"9;
"S \NAC"
BN"52"15;
%"TAP"
"6","(-5600,4175)","0","mstr_standard","I76";
;
CDS_LIB"mstr_standard"
BODY_TYPE"PLUMBING"
HDL_TAP"TRUE";
"B \NAC \NWC"9;
"S \NAC"
BN"53"85;
%"TAP"
"6","(-5600,4225)","0","mstr_standard","I77";
;
CDS_LIB"mstr_standard"
BODY_TYPE"PLUMBING"
HDL_TAP"TRUE";
"B \NAC \NWC"9;
"S \NAC"
BN"54"86;
%"TAP"
"6","(-5600,4275)","0","mstr_standard","I78";
;
CDS_LIB"mstr_standard"
BODY_TYPE"PLUMBING"
HDL_TAP"TRUE";
"B \NAC \NWC"9;
"S \NAC"
BN"55"13;
%"TAP"
"6","(-5600,4325)","0","mstr_standard","I79";
;
CDS_LIB"mstr_standard"
BODY_TYPE"PLUMBING"
HDL_TAP"TRUE";
"B \NAC \NWC"9;
"S \NAC"
BN"56"87;
%"TAP"
"6","(-5600,725)","0","mstr_standard","I8";
;
CDS_LIB"mstr_standard"
BODY_TYPE"PLUMBING"
HDL_TAP"TRUE";
"B \NAC \NWC"10;
"S \NAC"
BN"2"46;
%"TAP"
"6","(-5600,4375)","0","mstr_standard","I80";
;
CDS_LIB"mstr_standard"
BODY_TYPE"PLUMBING"
HDL_TAP"TRUE";
"B \NAC \NWC"9;
"S \NAC"
BN"57"88;
%"TAP"
"6","(-5600,4425)","0","mstr_standard","I81";
;
CDS_LIB"mstr_standard"
BODY_TYPE"PLUMBING"
HDL_TAP"TRUE";
"B \NAC \NWC"9;
"S \NAC"
BN"58"89;
%"TAP"
"6","(-5600,4475)","0","mstr_standard","I82";
;
CDS_LIB"mstr_standard"
BODY_TYPE"PLUMBING"
HDL_TAP"TRUE";
"B \NAC \NWC"9;
"S \NAC"
BN"59"90;
%"TAP"
"6","(-5600,4525)","0","mstr_standard","I83";
;
CDS_LIB"mstr_standard"
BODY_TYPE"PLUMBING"
HDL_TAP"TRUE";
"B \NAC \NWC"9;
"S \NAC"
BN"60"91;
%"TAP"
"6","(-5600,4575)","0","mstr_standard","I84";
;
CDS_LIB"mstr_standard"
BODY_TYPE"PLUMBING"
HDL_TAP"TRUE";
"B \NAC \NWC"9;
"S \NAC"
BN"61"92;
%"TAP"
"6","(-5600,4625)","0","mstr_standard","I85";
;
CDS_LIB"mstr_standard"
BODY_TYPE"PLUMBING"
HDL_TAP"TRUE";
"B \NAC \NWC"9;
"S \NAC"
BN"62"93;
%"TAP"
"6","(-5600,4675)","0","mstr_standard","I86";
;
CDS_LIB"mstr_standard"
BODY_TYPE"PLUMBING"
HDL_TAP"TRUE";
"B \NAC \NWC"9;
"S \NAC"
BN"63"94;
%"TAP"
"6","(-2875,775)","2","mstr_standard","I87";
;
CDS_LIB"mstr_standard"
BODY_TYPE"PLUMBING"
HDL_TAP"TRUE";
"B \NAC \NWC"4;
"S \NAC"
BN"1"116;
%"TAP"
"6","(-2875,725)","2","mstr_standard","I88";
;
CDS_LIB"mstr_standard"
BODY_TYPE"PLUMBING"
HDL_TAP"TRUE";
"B \NAC \NWC"4;
"S \NAC"
BN"0"115;
%"TAP"
"6","(-2875,825)","2","mstr_standard","I89";
;
CDS_LIB"mstr_standard"
BODY_TYPE"PLUMBING"
HDL_TAP"TRUE";
"B \NAC \NWC"5;
"S \NAC"
BN"0"113;
%"TAP"
"6","(-5600,875)","0","mstr_standard","I9";
;
CDS_LIB"mstr_standard"
BODY_TYPE"PLUMBING"
HDL_TAP"TRUE";
"B \NAC \NWC"11;
"S \NAC"
BN"1"41;
%"TAP"
"6","(-2875,875)","2","mstr_standard","I90";
;
CDS_LIB"mstr_standard"
BODY_TYPE"PLUMBING"
HDL_TAP"TRUE";
"B \NAC \NWC"5;
"S \NAC"
BN"1"114;
%"TAP"
"6","(-2875,1075)","2","mstr_standard","I91";
;
CDS_LIB"mstr_standard"
BODY_TYPE"PLUMBING"
HDL_TAP"TRUE";
"B \NAC \NWC"7;
"S \NAC"
BN"2"103;
%"TAP"
"6","(-2875,1025)","2","mstr_standard","I92";
;
CDS_LIB"mstr_standard"
BODY_TYPE"PLUMBING"
HDL_TAP"TRUE";
"B \NAC \NWC"7;
"S \NAC"
BN"1"102;
%"TAP"
"6","(-2875,975)","2","mstr_standard","I93";
;
CDS_LIB"mstr_standard"
BODY_TYPE"PLUMBING"
HDL_TAP"TRUE";
"B \NAC \NWC"7;
"S \NAC"
BN"0"101;
%"TAP"
"6","(-2875,1175)","2","mstr_standard","I94";
;
CDS_LIB"mstr_standard"
BODY_TYPE"PLUMBING"
HDL_TAP"TRUE";
"B \NAC \NWC"7;
"S \NAC"
BN"4"105;
%"TAP"
"6","(-2875,1125)","2","mstr_standard","I95";
;
CDS_LIB"mstr_standard"
BODY_TYPE"PLUMBING"
HDL_TAP"TRUE";
"B \NAC \NWC"7;
"S \NAC"
BN"3"104;
%"TAP"
"6","(-2875,1225)","2","mstr_standard","I96";
;
CDS_LIB"mstr_standard"
BODY_TYPE"PLUMBING"
HDL_TAP"TRUE";
"B \NAC \NWC"7;
"S \NAC"
BN"5"106;
%"TAP"
"6","(-2875,1275)","2","mstr_standard","I97";
;
CDS_LIB"mstr_standard"
BODY_TYPE"PLUMBING"
HDL_TAP"TRUE";
"B \NAC \NWC"7;
"S \NAC"
BN"6"107;
%"TAP"
"6","(-2875,1325)","2","mstr_standard","I98";
;
CDS_LIB"mstr_standard"
BODY_TYPE"PLUMBING"
HDL_TAP"TRUE";
"B \NAC \NWC"7;
"S \NAC"
BN"7"108;
%"TAP"
"6","(-2875,1425)","2","mstr_standard","I99";
;
CDS_LIB"mstr_standard"
BODY_TYPE"PLUMBING"
HDL_TAP"TRUE";
"B \NAC \NWC"8;
"S \NAC"
BN"0"95;
END.
